(kicad_pcb
	(version 20260206)
	(generator "pcbnew")
	(generator_version "10.0")
	(general
		(thickness 1.6)
		(legacy_teardrops no)
	)
	(paper "A4")
	(title_block
		(title "dpb — 14545-sa.0730WZS0815.brd")
		(comment 1 "Honey Badger (Wiwynn) / footprints 830-836 of 1066")
	)
	(layers
		(0 "F.Cu" signal "TOP")
		(4 "In1.Cu" signal "L2GND")
		(6 "In2.Cu" signal "L3")
		(8 "In3.Cu" signal "L4VCC")
		(10 "In4.Cu" signal "L5VCC")
		(12 "In5.Cu" signal "L6")
		(14 "In6.Cu" signal "L7GND")
		(2 "B.Cu" signal "BOTTOM")
		(9 "F.Adhes" user "F.Adhesive")
		(11 "B.Adhes" user "B.Adhesive")
		(13 "F.Paste" user "Package Geometry/Pastemask Top")
		(15 "B.Paste" user "Package Geometry/Pastemask Bottom")
		(5 "F.SilkS" user "Ref Des/Silkscreen Top")
		(7 "B.SilkS" user "Ref Des/Silkscreen Bottom")
		(1 "F.Mask" user "Board Geometry/Soldermask Top")
		(3 "B.Mask" user "Board Geometry/Soldermask Bottom")
		(17 "Dwgs.User" user "User.Drawings")
		(19 "Cmts.User" user "User.Comments")
		(21 "Eco1.User" user "User.Eco1")
		(23 "Eco2.User" user "User.Eco2")
		(25 "Edge.Cuts" user "Board Geometry/Outline")
		(27 "Margin" user)
		(31 "F.CrtYd" user "Package Geometry/Place Bound Top")
		(29 "B.CrtYd" user "Package Geometry/Place Bound Bottom")
		(35 "F.Fab" user "Ref Des/Assembly Top")
		(33 "B.Fab" user "Ref Des/Assembly Bottom")
	)
	(footprint ""
		(layer "F.Cu")
		(at 209.8294 -169.7736 180)
		(property "Reference" "R366"
			(at 0 0 180)
			(layer "F.SilkS")
			(hide yes)
			(effects
				(font
					(size 1.27 1.27)
				)
			)
		)
		(property "Value" "10KR2F-2-GP"
			(at 0.064008 -3.993896 180)
			(unlocked yes)
			(layer "F.Fab")
			(hide yes)
			(effects
				(font
					(size 1.016 1.016)
					(thickness 0.1524)
				)
			)
		)
		(property "Device Type" "R402H16"
			(at 0.064008 -5.517896 180)
			(unlocked yes)
			(layer "F.Fab")
			(hide yes)
			(effects
				(font
					(size 1.016 1.016)
					(thickness 0.1524)
				)
			)
		)
		(duplicate_pad_numbers_are_jumpers no)
		(fp_line
			(start 0.508 -0.9398)
			(end -0.508 -0.9398)
			(stroke
				(width 0.1524)
				(type default)
			)
			(layer "F.SilkS")
		)
		(fp_line
			(start -0.508 -0.9398)
			(end -0.508 0.9398)
			(stroke
				(width 0.1524)
				(type default)
			)
			(layer "F.SilkS")
		)
		(fp_rect
			(start -0.508 0.9398)
			(end 0.508 -0.9398)
			(stroke
				(width 0)
				(type default)
			)
			(fill no)
			(layer "F.CrtYd")
		)
		(fp_rect
			(start -0.508 0.9398)
			(end 0.508 -0.9398)
			(stroke
				(width 0)
				(type default)
			)
			(fill no)
			(layer "F.Fab")
		)
		(pad "1" smd custom
			(at 0 -0.4445 180)
			(size 0.1397 0.1397)
			(layers "F.Cu" "F.Mask" "F.Paste")
			(net "P12V")
			(options
				(clearance outline)
				(anchor circle)
			)
			(primitives
				(gr_poly
					(pts
						(arc
							(start -0.1778 -0.2794)
							(mid -0.249642 -0.249642)
							(end -0.2794 -0.1778)
						)
						(arc
							(start -0.2794 0.1778)
							(mid -0.249642 0.249642)
							(end -0.1778 0.2794)
						)
						(arc
							(start 0.1778 0.2794)
							(mid 0.249642 0.249642)
							(end 0.2794 0.1778)
						)
						(arc
							(start 0.2794 -0.1778)
							(mid 0.249642 -0.249642)
							(end 0.1778 -0.2794)
						)
					)
					(width 0)
					(fill yes)
				)
			)
		)
		(pad "2" smd custom
			(at 0 0.4445 180)
			(size 0.1397 0.1397)
			(layers "F.Cu" "F.Mask" "F.Paste")
			(net "HDD3_LED_G")
			(options
				(clearance outline)
				(anchor circle)
			)
			(primitives
				(gr_poly
					(pts
						(arc
							(start -0.1778 -0.2794)
							(mid -0.249642 -0.249642)
							(end -0.2794 -0.1778)
						)
						(arc
							(start -0.2794 0.1778)
							(mid -0.249642 0.249642)
							(end -0.1778 0.2794)
						)
						(arc
							(start 0.1778 0.2794)
							(mid 0.249642 0.249642)
							(end 0.2794 0.1778)
						)
						(arc
							(start 0.2794 -0.1778)
							(mid 0.249642 -0.249642)
							(end 0.1778 -0.2794)
						)
					)
					(width 0)
					(fill yes)
				)
			)
		)
	)
	(footprint ""
		(layer "F.Cu")
		(at 197.611746 -81.9277 -90)
		(property "Reference" "R441"
			(at 0 0 270)
			(layer "F.SilkS")
			(hide yes)
			(effects
				(font
					(size 1.27 1.27)
				)
			)
		)
		(property "Value" "4K7R2J-2-GP"
			(at 0.064008 -3.993896 270)
			(unlocked yes)
			(layer "F.Fab")
			(hide yes)
			(effects
				(font
					(size 1.016 1.016)
					(thickness 0.1524)
				)
			)
		)
		(property "Device Type" "R402H16"
			(at 0.064008 -5.517896 270)
			(unlocked yes)
			(layer "F.Fab")
			(hide yes)
			(effects
				(font
					(size 1.016 1.016)
					(thickness 0.1524)
				)
			)
		)
		(duplicate_pad_numbers_are_jumpers no)
		(fp_line
			(start -0.508 -0.9398)
			(end -0.508 0.9398)
			(stroke
				(width 0.1524)
				(type default)
			)
			(layer "F.SilkS")
		)
		(fp_line
			(start 0.508 -0.9398)
			(end -0.508 -0.9398)
			(stroke
				(width 0.1524)
				(type default)
			)
			(layer "F.SilkS")
		)
		(fp_rect
			(start -0.508 0.9398)
			(end 0.508 -0.9398)
			(stroke
				(width 0)
				(type default)
			)
			(fill no)
			(layer "F.CrtYd")
		)
		(fp_rect
			(start -0.508 0.9398)
			(end 0.508 -0.9398)
			(stroke
				(width 0)
				(type default)
			)
			(fill no)
			(layer "F.Fab")
		)
		(pad "1" smd custom
			(at 0 -0.4445 270)
			(size 0.1397 0.1397)
			(layers "F.Cu" "F.Mask" "F.Paste")
			(net "P3V3")
			(options
				(clearance outline)
				(anchor circle)
			)
			(primitives
				(gr_poly
					(pts
						(arc
							(start -0.1778 -0.2794)
							(mid -0.249642 -0.249642)
							(end -0.2794 -0.1778)
						)
						(arc
							(start -0.2794 0.1778)
							(mid -0.249642 0.249642)
							(end -0.1778 0.2794)
						)
						(arc
							(start 0.1778 0.2794)
							(mid 0.249642 0.249642)
							(end 0.2794 0.1778)
						)
						(arc
							(start 0.2794 -0.1778)
							(mid 0.249642 -0.249642)
							(end 0.1778 -0.2794)
						)
					)
					(width 0)
					(fill yes)
				)
			)
		)
		(pad "2" smd custom
			(at 0 0.4445 270)
			(size 0.1397 0.1397)
			(layers "F.Cu" "F.Mask" "F.Paste")
			(net "SAS_EXP_B_PWR4")
			(options
				(clearance outline)
				(anchor circle)
			)
			(primitives
				(gr_poly
					(pts
						(arc
							(start -0.1778 -0.2794)
							(mid -0.249642 -0.249642)
							(end -0.2794 -0.1778)
						)
						(arc
							(start -0.2794 0.1778)
							(mid -0.249642 0.249642)
							(end -0.1778 0.2794)
						)
						(arc
							(start 0.1778 0.2794)
							(mid 0.249642 0.249642)
							(end 0.2794 0.1778)
						)
						(arc
							(start 0.2794 -0.1778)
							(mid 0.249642 -0.249642)
							(end 0.1778 -0.2794)
						)
					)
					(width 0)
					(fill yes)
				)
			)
		)
	)
	(footprint ""
		(layer "F.Cu")
		(at 230.267256 -451.513702 90)
		(property "Reference" "R105"
			(at 0 0 90)
			(layer "F.SilkS")
			(hide yes)
			(effects
				(font
					(size 1.27 1.27)
				)
			)
		)
		(property "Value" "0R2J-2-GP"
			(at 0.064008 -3.993896 90)
			(unlocked yes)
			(layer "F.Fab")
			(hide yes)
			(effects
				(font
					(size 1.016 1.016)
					(thickness 0.1524)
				)
			)
		)
		(property "Device Type" "R402H16"
			(at 0.064008 -5.517896 90)
			(unlocked yes)
			(layer "F.Fab")
			(hide yes)
			(effects
				(font
					(size 1.016 1.016)
					(thickness 0.1524)
				)
			)
		)
		(duplicate_pad_numbers_are_jumpers no)
		(fp_line
			(start 0.508 -0.9398)
			(end -0.508 -0.9398)
			(stroke
				(width 0.1524)
				(type default)
			)
			(layer "F.SilkS")
		)
		(fp_line
			(start -0.508 -0.9398)
			(end -0.508 0.9398)
			(stroke
				(width 0.1524)
				(type default)
			)
			(layer "F.SilkS")
		)
		(fp_rect
			(start -0.508 0.9398)
			(end 0.508 -0.9398)
			(stroke
				(width 0)
				(type default)
			)
			(fill no)
			(layer "F.CrtYd")
		)
		(fp_rect
			(start -0.508 0.9398)
			(end 0.508 -0.9398)
			(stroke
				(width 0)
				(type default)
			)
			(fill no)
			(layer "F.Fab")
		)
		(pad "1" smd custom
			(at 0 -0.4445 90)
			(size 0.1397 0.1397)
			(layers "F.Cu" "F.Mask" "F.Paste")
			(net "FLT_NET_HDD0")
			(options
				(clearance outline)
				(anchor circle)
			)
			(primitives
				(gr_poly
					(pts
						(arc
							(start -0.1778 -0.2794)
							(mid -0.249642 -0.249642)
							(end -0.2794 -0.1778)
						)
						(arc
							(start -0.2794 0.1778)
							(mid -0.249642 0.249642)
							(end -0.1778 0.2794)
						)
						(arc
							(start 0.1778 0.2794)
							(mid 0.249642 0.249642)
							(end 0.2794 0.1778)
						)
						(arc
							(start 0.2794 -0.1778)
							(mid 0.249642 -0.249642)
							(end 0.1778 -0.2794)
						)
					)
					(width 0)
					(fill yes)
				)
			)
		)
		(pad "2" smd custom
			(at 0 0.4445 90)
			(size 0.1397 0.1397)
			(layers "F.Cu" "F.Mask" "F.Paste")
			(net "FLT_HDD0_DRIVE")
			(options
				(clearance outline)
				(anchor circle)
			)
			(primitives
				(gr_poly
					(pts
						(arc
							(start -0.1778 -0.2794)
							(mid -0.249642 -0.249642)
							(end -0.2794 -0.1778)
						)
						(arc
							(start -0.2794 0.1778)
							(mid -0.249642 0.249642)
							(end -0.1778 0.2794)
						)
						(arc
							(start 0.1778 0.2794)
							(mid 0.249642 0.249642)
							(end 0.2794 0.1778)
						)
						(arc
							(start 0.2794 -0.1778)
							(mid 0.249642 -0.249642)
							(end 0.1778 -0.2794)
						)
					)
					(width 0)
					(fill yes)
				)
			)
		)
	)
	(footprint ""
		(layer "F.Cu")
		(at 9.651746 -487.1847 90)
		(property "Reference" "PC28"
			(at 0 0 90)
			(layer "F.SilkS")
			(hide yes)
			(effects
				(font
					(size 1.27 1.27)
				)
			)
		)
		(property "Value" "SCD1U25V2KX-GP"
			(at 1.1811 -2.7051 90)
			(unlocked yes)
			(layer "F.Fab")
			(hide yes)
			(effects
				(font
					(size 1.016 1.016)
					(thickness 0.1524)
				)
			)
		)
		(property "Device Type" "C402H22"
			(at 1.1811 -4.2291 90)
			(unlocked yes)
			(layer "F.Fab")
			(hide yes)
			(effects
				(font
					(size 1.016 1.016)
					(thickness 0.1524)
				)
			)
		)
		(duplicate_pad_numbers_are_jumpers no)
		(fp_rect
			(start -0.4318 0.9525)
			(end 0.4318 -0.9525)
			(stroke
				(width 0)
				(type default)
			)
			(fill no)
			(layer "F.CrtYd")
		)
		(fp_rect
			(start -0.4318 0.9525)
			(end 0.4318 -0.9525)
			(stroke
				(width 0)
				(type default)
			)
			(fill no)
			(layer "F.Fab")
		)
		(pad "1" smd custom
			(at 0 -0.4445 90)
			(size 0.1524 0.1524)
			(layers "F.Cu" "F.Mask" "F.Paste")
			(net "P5VC_VBST_NET")
			(options
				(clearance outline)
				(anchor circle)
			)
			(primitives
				(gr_poly
					(pts
						(arc
							(start 0.3048 -0.2032)
							(mid 0.275042 -0.275042)
							(end 0.2032 -0.3048)
						)
						(arc
							(start -0.2032 -0.3048)
							(mid -0.275042 -0.275042)
							(end -0.3048 -0.2032)
						)
						(arc
							(start -0.3048 0.2032)
							(mid -0.275042 0.275042)
							(end -0.2032 0.3048)
						)
						(arc
							(start 0.2032 0.3048)
							(mid 0.275042 0.275042)
							(end 0.3048 0.2032)
						)
					)
					(width 0)
					(fill yes)
				)
			)
		)
		(pad "2" smd custom
			(at 0 0.4445 90)
			(size 0.1524 0.1524)
			(layers "F.Cu" "F.Mask" "F.Paste")
			(net "P5VC_LL")
			(options
				(clearance outline)
				(anchor circle)
			)
			(primitives
				(gr_poly
					(pts
						(arc
							(start 0.3048 -0.2032)
							(mid 0.275042 -0.275042)
							(end 0.2032 -0.3048)
						)
						(arc
							(start -0.2032 -0.3048)
							(mid -0.275042 -0.275042)
							(end -0.3048 -0.2032)
						)
						(arc
							(start -0.3048 0.2032)
							(mid -0.275042 0.275042)
							(end -0.2032 0.3048)
						)
						(arc
							(start 0.2032 0.3048)
							(mid 0.275042 0.275042)
							(end 0.3048 0.2032)
						)
					)
					(width 0)
					(fill yes)
				)
			)
		)
	)
	(footprint ""
		(layer "F.Cu")
		(at 58.166 -497.6114 180)
		(property "Reference" "C193"
			(at 0 0 180)
			(layer "F.SilkS")
			(hide yes)
			(effects
				(font
					(size 1.27 1.27)
				)
			)
		)
		(property "Value" "SC10U25V6KX-1GP"
			(at -0.0762 -5.1308 180)
			(unlocked yes)
			(layer "F.Fab")
			(hide yes)
			(effects
				(font
					(size 1.016 1.016)
					(thickness 0.1524)
				)
			)
		)
		(property "Device Type" "C1206H71"
			(at -0.127 -6.6548 180)
			(unlocked yes)
			(layer "F.Fab")
			(hide yes)
			(effects
				(font
					(size 1.016 1.016)
					(thickness 0.1524)
				)
			)
		)
		(duplicate_pad_numbers_are_jumpers no)
		(fp_line
			(start 1.016 2.2352)
			(end -1.016 2.2352)
			(stroke
				(width 0.1524)
				(type default)
			)
			(layer "F.SilkS")
		)
		(fp_line
			(start 1.016 0.8382)
			(end 1.016 2.2352)
			(stroke
				(width 0.1524)
				(type default)
			)
			(layer "F.SilkS")
		)
		(fp_line
			(start 1.016 -2.2352)
			(end 1.016 -0.8382)
			(stroke
				(width 0.1524)
				(type default)
			)
			(layer "F.SilkS")
		)
		(fp_line
			(start -1.016 2.2352)
			(end -1.016 0.8382)
			(stroke
				(width 0.1524)
				(type default)
			)
			(layer "F.SilkS")
		)
		(fp_line
			(start -1.016 -0.8382)
			(end -1.016 -2.2352)
			(stroke
				(width 0.1524)
				(type default)
			)
			(layer "F.SilkS")
		)
		(fp_line
			(start -1.016 -2.2352)
			(end 1.016 -2.2352)
			(stroke
				(width 0.1524)
				(type default)
			)
			(layer "F.SilkS")
		)
		(fp_rect
			(start -1.0922 2.3114)
			(end 1.0922 -2.3114)
			(stroke
				(width 0)
				(type default)
			)
			(fill no)
			(layer "F.CrtYd")
		)
		(fp_poly
			(pts
				(xy 1.0922 -2.3114) (xy 1.0922 2.3114) (xy -1.0922 2.3114) (xy -1.0922 -2.3114)
			)
			(stroke
				(width 0)
				(type default)
			)
			(fill no)
			(layer "F.Fab")
		)
		(pad "1" smd rect
			(at 0 -1.397 180)
			(size 1.651 1.27)
			(layers "F.Cu" "F.Mask" "F.Paste")
			(net "P12V_HDD5")
		)
		(pad "2" smd rect
			(at 0 1.397 180)
			(size 1.651 1.27)
			(layers "F.Cu" "F.Mask" "F.Paste")
			(net "GND")
		)
	)
	(footprint ""
		(layer "F.Cu")
		(at 58.149236 -484.298498 90)
		(property "Reference" "R175"
			(at 0 0 90)
			(layer "F.SilkS")
			(hide yes)
			(effects
				(font
					(size 1.27 1.27)
				)
			)
		)
		(property "Value" "2R2010J-1-GP"
			(at 0.254 -8.0772 90)
			(unlocked yes)
			(layer "F.Fab")
			(hide yes)
			(effects
				(font
					(size 1.016 1.016)
					(thickness 0.1524)
				)
			)
		)
		(property "Device Type" "R2010H28"
			(at 0.254 -9.6774 90)
			(unlocked yes)
			(layer "F.Fab")
			(hide yes)
			(effects
				(font
					(size 1.016 1.016)
					(thickness 0.1524)
				)
			)
		)
		(duplicate_pad_numbers_are_jumpers no)
		(fp_line
			(start 1.651 -3.302)
			(end -1.651 -3.302)
			(stroke
				(width 0.1524)
				(type default)
			)
			(layer "F.SilkS")
		)
		(fp_line
			(start -1.651 -3.302)
			(end -1.651 3.302)
			(stroke
				(width 0.1524)
				(type default)
			)
			(layer "F.SilkS")
		)
		(fp_line
			(start 1.651 3.302)
			(end 1.651 -3.302)
			(stroke
				(width 0.1524)
				(type default)
			)
			(layer "F.SilkS")
		)
		(fp_line
			(start -1.651 3.302)
			(end 1.651 3.302)
			(stroke
				(width 0.1524)
				(type default)
			)
			(layer "F.SilkS")
		)
		(fp_rect
			(start -1.7272 -3.3782)
			(end 1.7272 3.3782)
			(stroke
				(width 0)
				(type default)
			)
			(fill no)
			(layer "F.CrtYd")
		)
		(fp_poly
			(pts
				(xy 1.7272 3.3782) (xy 1.7272 -3.3782) (xy -1.7272 -3.3782) (xy -1.7272 3.3782)
			)
			(stroke
				(width 0)
				(type default)
			)
			(fill no)
			(layer "F.Fab")
		)
		(pad "1" smd rect
			(at 0 -2.3495 90)
			(size 2.794 1.143)
			(layers "F.Cu" "F.Mask" "F.Paste")
			(net "5V_PRE_5")
		)
		(pad "2" smd rect
			(at 0 2.3495 90)
			(size 2.794 1.143)
			(layers "F.Cu" "F.Mask" "F.Paste")
			(net "P5V_HDD5")
		)
	)
	(footprint ""
		(layer "F.Cu")
		(at 212.1662 -171.1706 180)
		(property "Reference" "Q53"
			(at 0 0 180)
			(layer "F.SilkS")
			(hide yes)
			(effects
				(font
					(size 1.27 1.27)
				)
			)
		)
		(property "Value" "2N7002-11-GP"
			(at 0.127 -8.9662 180)
			(unlocked yes)
			(layer "F.Fab")
			(hide yes)
			(effects
				(font
					(size 1.016 1.016)
					(thickness 0.1524)
				)
			)
		)
		(property "Device Type" "SOT23DGS2D4H44"
			(at 0.127 -10.4902 180)
			(unlocked yes)
			(layer "F.Fab")
			(hide yes)
			(effects
				(font
					(size 1.016 1.016)
					(thickness 0.1524)
				)
			)
		)
		(duplicate_pad_numbers_are_jumpers no)
		(fp_line
			(start 1.651 1.778)
			(end 1.651 -1.778)
			(stroke
				(width 0.1524)
				(type default)
			)
			(layer "F.SilkS")
		)
		(fp_line
			(start 1.651 -1.778)
			(end -1.651 -1.778)
			(stroke
				(width 0.1524)
				(type default)
			)
			(layer "F.SilkS")
		)
		(fp_line
			(start -1.651 1.778)
			(end 1.651 1.778)
			(stroke
				(width 0.1524)
				(type default)
			)
			(layer "F.SilkS")
		)
		(fp_line
			(start -1.651 -1.778)
			(end -1.651 1.778)
			(stroke
				(width 0.1524)
				(type default)
			)
			(layer "F.SilkS")
		)
		(fp_poly
			(pts
				(xy -1.778 1.8796) (xy -1.778 -1.8796) (xy 1.778 -1.8796) (xy 1.778 1.8796)
			)
			(stroke
				(width 0)
				(type default)
			)
			(fill no)
			(layer "F.CrtYd")
		)
		(fp_poly
			(pts
				(xy -1.778 1.8796) (xy -1.778 -1.8796) (xy 1.778 -1.8796) (xy 1.778 1.8796)
			)
			(stroke
				(width 0)
				(type default)
			)
			(fill no)
			(layer "F.Fab")
		)
		(pad "D" smd custom
			(at 0 -0.9525 180)
			(size 0.1905 0.1905)
			(layers "F.Cu" "F.Mask" "F.Paste")
			(net "HDD3_LED_G")
			(options
				(clearance outline)
				(anchor circle)
			)
			(primitives
				(gr_poly
					(pts
						(arc
							(start -0.1778 0.5715)
							(mid -0.321484 0.511984)
							(end -0.381 0.3683)
						)
						(arc
							(start -0.381 -0.3683)
							(mid -0.321484 -0.511984)
							(end -0.1778 -0.5715)
						)
						(arc
							(start 0.1778 -0.5715)
							(mid 0.321484 -0.511984)
							(end 0.381 -0.3683)
						)
						(arc
							(start 0.381 0.3683)
							(mid 0.321484 0.511984)
							(end 0.1778 0.5715)
						)
					)
					(width 0)
					(fill yes)
				)
			)
		)
		(pad "G" smd custom
			(at -0.98425 0.9525 180)
			(size 0.1905 0.1905)
			(layers "F.Cu" "F.Mask" "F.Paste")
			(net "HDD3_LED_B")
			(options
				(clearance outline)
				(anchor circle)
			)
			(primitives
				(gr_poly
					(pts
						(arc
							(start -0.1778 0.5715)
							(mid -0.321484 0.511984)
							(end -0.381 0.3683)
						)
						(arc
							(start -0.381 -0.3683)
							(mid -0.321484 -0.511984)
							(end -0.1778 -0.5715)
						)
						(arc
							(start 0.1778 -0.5715)
							(mid 0.321484 -0.511984)
							(end 0.381 -0.3683)
						)
						(arc
							(start 0.381 0.3683)
							(mid 0.321484 0.511984)
							(end 0.1778 0.5715)
						)
					)
					(width 0)
					(fill yes)
				)
			)
		)
		(pad "S" smd custom
			(at 0.98425 0.9525 180)
			(size 0.1905 0.1905)
			(layers "F.Cu" "F.Mask" "F.Paste")
			(net "GND")
			(options
				(clearance outline)
				(anchor circle)
			)
			(primitives
				(gr_poly
					(pts
						(arc
							(start -0.1778 0.5715)
							(mid -0.321484 0.511984)
							(end -0.381 0.3683)
						)
						(arc
							(start -0.381 -0.3683)
							(mid -0.321484 -0.511984)
							(end -0.1778 -0.5715)
						)
						(arc
							(start 0.1778 -0.5715)
							(mid 0.321484 -0.511984)
							(end 0.381 -0.3683)
						)
						(arc
							(start 0.381 0.3683)
							(mid 0.321484 0.511984)
							(end 0.1778 0.5715)
						)
					)
					(width 0)
					(fill yes)
				)
			)
		)
	)
)
